(kicad_pcb
	(version 20260206)
	(generator "pcbnew")
	(generator_version "10.0")
	(general
		(thickness 1.6)
		(legacy_teardrops no)
	)
	(paper "A4")
	(title_block
		(title "03242023_DA0F0TMBIJ0_F0T_Motherboard_J_brd_V01_OCP.brd")
		(comment 1 "Grand Teton / footprints 2059-2064 of 6105")
	)
	(layers
		(0 "F.Cu" signal "TOP")
		(4 "In1.Cu" signal "GND")
		(6 "In2.Cu" signal "IN1")
		(8 "In3.Cu" signal "GND1")
		(10 "In4.Cu" signal "IN2")
		(12 "In5.Cu" signal "GND2")
		(14 "In6.Cu" signal "IN3")
		(16 "In7.Cu" signal "GND3")
		(18 "In8.Cu" signal "VCC")
		(20 "In9.Cu" signal "VCC1")
		(22 "In10.Cu" signal "GND4")
		(24 "In11.Cu" signal "IN4")
		(26 "In12.Cu" signal "GND5")
		(28 "In13.Cu" signal "IN5")
		(30 "In14.Cu" signal "GND6")
		(32 "In15.Cu" signal "IN6")
		(34 "In16.Cu" signal "GND7")
		(2 "B.Cu" signal "BOTTOM")
		(9 "F.Adhes" user "F.Adhesive")
		(11 "B.Adhes" user "B.Adhesive")
		(13 "F.Paste" user "Package Geometry/Pastemask Top")
		(15 "B.Paste" user "Package Geometry/Pastemask Bottom")
		(5 "F.SilkS" user "Ref Des/Silkscreen Top")
		(7 "B.SilkS" user "Ref Des/Silkscreen Bottom")
		(1 "F.Mask" user "Board Geometry/Soldermask Top")
		(3 "B.Mask" user "Board Geometry/Soldermask Bottom")
		(17 "Dwgs.User" user "User.Drawings")
		(19 "Cmts.User" user "User.Comments")
		(21 "Eco1.User" user "User.Eco1")
		(23 "Eco2.User" user "User.Eco2")
		(25 "Edge.Cuts" user "Board Geometry/Outline")
		(27 "Margin" user)
		(31 "F.CrtYd" user "Package Geometry/Place Bound Top")
		(29 "B.CrtYd" user "Package Geometry/Place Bound Bottom")
		(35 "F.Fab" user "Ref Des/Assembly Top")
		(33 "B.Fab" user "Ref Des/Assembly Bottom")
	)
	(footprint ""
		(layer "F.Cu")
		(at 197.19036 -119.344948)
		(property "Reference" "R1421"
			(at 0 0 0)
			(layer "F.SilkS")
			(hide yes)
			(effects
				(font
					(size 1.27 1.27)
				)
			)
		)
		(property "Value" ""
			(at 0 0 0)
			(layer "F.Fab")
			(effects
				(font
					(size 1.27 1.27)
				)
			)
		)
		(duplicate_pad_numbers_are_jumpers no)
		(fp_line
			(start -0.7874 -0.4064)
			(end 0.7874 -0.4064)
			(stroke
				(width 0.1524)
				(type default)
			)
			(layer "F.SilkS")
		)
		(fp_line
			(start -0.7874 0.4064)
			(end -0.7874 -0.4064)
			(stroke
				(width 0.1524)
				(type default)
			)
			(layer "F.SilkS")
		)
		(fp_line
			(start 0.7874 -0.4064)
			(end 0.7874 0.4064)
			(stroke
				(width 0.1524)
				(type default)
			)
			(layer "F.SilkS")
		)
		(fp_line
			(start 0.7874 0.4064)
			(end -0.7874 0.4064)
			(stroke
				(width 0.1524)
				(type default)
			)
			(layer "F.SilkS")
		)
		(fp_line
			(start -0.67945 -0.305054)
			(end -0.12065 -0.305054)
			(stroke
				(width 0.1)
				(type default)
			)
			(layer "F.Fab")
		)
		(fp_line
			(start -0.67945 0.3048)
			(end -0.67945 -0.305054)
			(stroke
				(width 0.1)
				(type default)
			)
			(layer "F.Fab")
		)
		(fp_line
			(start -0.12065 -0.305054)
			(end -0.12065 -0.2794)
			(stroke
				(width 0.1)
				(type default)
			)
			(layer "F.Fab")
		)
		(fp_line
			(start -0.12065 -0.2794)
			(end 0.12065 -0.2794)
			(stroke
				(width 0.1)
				(type default)
			)
			(layer "F.Fab")
		)
		(fp_line
			(start -0.12065 0.2794)
			(end -0.12065 0.3048)
			(stroke
				(width 0.1)
				(type default)
			)
			(layer "F.Fab")
		)
		(fp_line
			(start -0.12065 0.3048)
			(end -0.67945 0.3048)
			(stroke
				(width 0.1)
				(type default)
			)
			(layer "F.Fab")
		)
		(fp_line
			(start 0.120396 0.2794)
			(end -0.12065 0.2794)
			(stroke
				(width 0.1)
				(type default)
			)
			(layer "F.Fab")
		)
		(fp_line
			(start 0.120396 0.3048)
			(end 0.120396 0.2794)
			(stroke
				(width 0.1)
				(type default)
			)
			(layer "F.Fab")
		)
		(fp_line
			(start 0.12065 -0.3048)
			(end 0.67945 -0.3048)
			(stroke
				(width 0.1)
				(type default)
			)
			(layer "F.Fab")
		)
		(fp_line
			(start 0.12065 -0.2794)
			(end 0.12065 -0.3048)
			(stroke
				(width 0.1)
				(type default)
			)
			(layer "F.Fab")
		)
		(fp_line
			(start 0.67945 -0.3048)
			(end 0.67945 0.3048)
			(stroke
				(width 0.1)
				(type default)
			)
			(layer "F.Fab")
		)
		(fp_line
			(start 0.67945 0.3048)
			(end 0.120396 0.3048)
			(stroke
				(width 0.1)
				(type default)
			)
			(layer "F.Fab")
		)
		(pad "1" smd circle
			(at -0.40005 0)
			(size 0 0)
			(layers "F.Cu" "F.Mask" "F.Paste")
			(net "RST_RSMRST_PLD_R_N")
		)
		(pad "2" smd circle
			(at 0.40005 0)
			(size 0 0)
			(layers "F.Cu" "F.Mask" "F.Paste")
			(net "GND")
		)
	)
	(footprint ""
		(layer "F.Cu")
		(at 24.046942 -415.127948 180)
		(property "Reference" "C1756"
			(at 0 0 180)
			(layer "F.SilkS")
			(hide yes)
			(effects
				(font
					(size 1.27 1.27)
				)
			)
		)
		(property "Value" ""
			(at 0 0 180)
			(layer "F.Fab")
			(effects
				(font
					(size 1.27 1.27)
				)
			)
		)
		(duplicate_pad_numbers_are_jumpers no)
		(fp_line
			(start 0.7874 0.4064)
			(end -0.7874 0.4064)
			(stroke
				(width 0.1524)
				(type default)
			)
			(layer "F.SilkS")
		)
		(fp_line
			(start 0.7874 -0.4064)
			(end 0.7874 0.4064)
			(stroke
				(width 0.1524)
				(type default)
			)
			(layer "F.SilkS")
		)
		(fp_line
			(start -0.7874 0.4064)
			(end -0.7874 -0.4064)
			(stroke
				(width 0.1524)
				(type default)
			)
			(layer "F.SilkS")
		)
		(fp_line
			(start -0.7874 -0.4064)
			(end 0.7874 -0.4064)
			(stroke
				(width 0.1524)
				(type default)
			)
			(layer "F.SilkS")
		)
		(fp_line
			(start 0.67945 0.3048)
			(end 0.120396 0.3048)
			(stroke
				(width 0.1)
				(type default)
			)
			(layer "F.Fab")
		)
		(fp_line
			(start 0.67945 -0.3048)
			(end 0.67945 0.3048)
			(stroke
				(width 0.1)
				(type default)
			)
			(layer "F.Fab")
		)
		(fp_line
			(start 0.12065 -0.2794)
			(end 0.12065 -0.3048)
			(stroke
				(width 0.1)
				(type default)
			)
			(layer "F.Fab")
		)
		(fp_line
			(start 0.12065 -0.3048)
			(end 0.67945 -0.3048)
			(stroke
				(width 0.1)
				(type default)
			)
			(layer "F.Fab")
		)
		(fp_line
			(start 0.120396 0.3048)
			(end 0.120396 0.2794)
			(stroke
				(width 0.1)
				(type default)
			)
			(layer "F.Fab")
		)
		(fp_line
			(start 0.120396 0.2794)
			(end -0.12065 0.2794)
			(stroke
				(width 0.1)
				(type default)
			)
			(layer "F.Fab")
		)
		(fp_line
			(start -0.12065 0.3048)
			(end -0.67945 0.3048)
			(stroke
				(width 0.1)
				(type default)
			)
			(layer "F.Fab")
		)
		(fp_line
			(start -0.12065 0.2794)
			(end -0.12065 0.3048)
			(stroke
				(width 0.1)
				(type default)
			)
			(layer "F.Fab")
		)
		(fp_line
			(start -0.12065 -0.2794)
			(end 0.12065 -0.2794)
			(stroke
				(width 0.1)
				(type default)
			)
			(layer "F.Fab")
		)
		(fp_line
			(start -0.12065 -0.305054)
			(end -0.12065 -0.2794)
			(stroke
				(width 0.1)
				(type default)
			)
			(layer "F.Fab")
		)
		(fp_line
			(start -0.67945 0.3048)
			(end -0.67945 -0.305054)
			(stroke
				(width 0.1)
				(type default)
			)
			(layer "F.Fab")
		)
		(fp_line
			(start -0.67945 -0.305054)
			(end -0.12065 -0.305054)
			(stroke
				(width 0.1)
				(type default)
			)
			(layer "F.Fab")
		)
		(pad "1" smd circle
			(at -0.40005 0 180)
			(size 0 0)
			(layers "F.Cu" "F.Mask" "F.Paste")
			(net "FM_GPU_PWRGD_ISO")
		)
		(pad "2" smd circle
			(at 0.40005 0 180)
			(size 0 0)
			(layers "F.Cu" "F.Mask" "F.Paste")
			(net "GND")
		)
	)
	(footprint ""
		(layer "F.Cu")
		(at 126.534926 -122.096784 90)
		(property "Reference" "R939"
			(at 0 0 90)
			(layer "F.SilkS")
			(hide yes)
			(effects
				(font
					(size 1.27 1.27)
				)
			)
		)
		(property "Value" ""
			(at 0 0 90)
			(layer "F.Fab")
			(effects
				(font
					(size 1.27 1.27)
				)
			)
		)
		(duplicate_pad_numbers_are_jumpers no)
		(fp_line
			(start 0.7874 -0.4064)
			(end 0.7874 0.4064)
			(stroke
				(width 0.1524)
				(type default)
			)
			(layer "F.SilkS")
		)
		(fp_line
			(start -0.7874 -0.4064)
			(end 0.7874 -0.4064)
			(stroke
				(width 0.1524)
				(type default)
			)
			(layer "F.SilkS")
		)
		(fp_line
			(start 0.7874 0.4064)
			(end -0.7874 0.4064)
			(stroke
				(width 0.1524)
				(type default)
			)
			(layer "F.SilkS")
		)
		(fp_line
			(start -0.7874 0.4064)
			(end -0.7874 -0.4064)
			(stroke
				(width 0.1524)
				(type default)
			)
			(layer "F.SilkS")
		)
		(fp_line
			(start -0.12065 -0.305054)
			(end -0.12065 -0.2794)
			(stroke
				(width 0.1)
				(type default)
			)
			(layer "F.Fab")
		)
		(fp_line
			(start -0.67945 -0.305054)
			(end -0.12065 -0.305054)
			(stroke
				(width 0.1)
				(type default)
			)
			(layer "F.Fab")
		)
		(fp_line
			(start 0.67945 -0.3048)
			(end 0.67945 0.3048)
			(stroke
				(width 0.1)
				(type default)
			)
			(layer "F.Fab")
		)
		(fp_line
			(start 0.12065 -0.3048)
			(end 0.67945 -0.3048)
			(stroke
				(width 0.1)
				(type default)
			)
			(layer "F.Fab")
		)
		(fp_line
			(start 0.12065 -0.2794)
			(end 0.12065 -0.3048)
			(stroke
				(width 0.1)
				(type default)
			)
			(layer "F.Fab")
		)
		(fp_line
			(start -0.12065 -0.2794)
			(end 0.12065 -0.2794)
			(stroke
				(width 0.1)
				(type default)
			)
			(layer "F.Fab")
		)
		(fp_line
			(start 0.120396 0.2794)
			(end -0.12065 0.2794)
			(stroke
				(width 0.1)
				(type default)
			)
			(layer "F.Fab")
		)
		(fp_line
			(start -0.12065 0.2794)
			(end -0.12065 0.3048)
			(stroke
				(width 0.1)
				(type default)
			)
			(layer "F.Fab")
		)
		(fp_line
			(start 0.67945 0.3048)
			(end 0.120396 0.3048)
			(stroke
				(width 0.1)
				(type default)
			)
			(layer "F.Fab")
		)
		(fp_line
			(start 0.120396 0.3048)
			(end 0.120396 0.2794)
			(stroke
				(width 0.1)
				(type default)
			)
			(layer "F.Fab")
		)
		(fp_line
			(start -0.12065 0.3048)
			(end -0.67945 0.3048)
			(stroke
				(width 0.1)
				(type default)
			)
			(layer "F.Fab")
		)
		(fp_line
			(start -0.67945 0.3048)
			(end -0.67945 -0.305054)
			(stroke
				(width 0.1)
				(type default)
			)
			(layer "F.Fab")
		)
		(pad "1" smd circle
			(at -0.40005 0 90)
			(size 0 0)
			(layers "F.Cu" "F.Mask" "F.Paste")
			(net "RST_CPU1_DRAM_GH_N")
		)
		(pad "2" smd circle
			(at 0.40005 0 90)
			(size 0 0)
			(layers "F.Cu" "F.Mask" "F.Paste")
			(net "GND")
		)
	)
	(footprint ""
		(layer "F.Cu")
		(at 52.759864 -358.20223 -90)
		(property "Reference" "PC402"
			(at 0 0 270)
			(layer "F.SilkS")
			(hide yes)
			(effects
				(font
					(size 1.27 1.27)
				)
			)
		)
		(property "Value" ""
			(at 0 0 270)
			(layer "F.Fab")
			(effects
				(font
					(size 1.27 1.27)
				)
			)
		)
		(duplicate_pad_numbers_are_jumpers no)
		(fp_line
			(start -0.7874 0.4064)
			(end -0.7874 -0.4064)
			(stroke
				(width 0.1524)
				(type default)
			)
			(layer "F.SilkS")
		)
		(fp_line
			(start 0.7874 0.4064)
			(end -0.7874 0.4064)
			(stroke
				(width 0.1524)
				(type default)
			)
			(layer "F.SilkS")
		)
		(fp_line
			(start -0.7874 -0.4064)
			(end 0.7874 -0.4064)
			(stroke
				(width 0.1524)
				(type default)
			)
			(layer "F.SilkS")
		)
		(fp_line
			(start 0.7874 -0.4064)
			(end 0.7874 0.4064)
			(stroke
				(width 0.1524)
				(type default)
			)
			(layer "F.SilkS")
		)
		(fp_line
			(start -0.67945 0.3048)
			(end -0.67945 -0.305054)
			(stroke
				(width 0.1)
				(type default)
			)
			(layer "F.Fab")
		)
		(fp_line
			(start -0.12065 0.3048)
			(end -0.67945 0.3048)
			(stroke
				(width 0.1)
				(type default)
			)
			(layer "F.Fab")
		)
		(fp_line
			(start 0.120396 0.3048)
			(end 0.120396 0.2794)
			(stroke
				(width 0.1)
				(type default)
			)
			(layer "F.Fab")
		)
		(fp_line
			(start 0.67945 0.3048)
			(end 0.120396 0.3048)
			(stroke
				(width 0.1)
				(type default)
			)
			(layer "F.Fab")
		)
		(fp_line
			(start -0.12065 0.2794)
			(end -0.12065 0.3048)
			(stroke
				(width 0.1)
				(type default)
			)
			(layer "F.Fab")
		)
		(fp_line
			(start 0.120396 0.2794)
			(end -0.12065 0.2794)
			(stroke
				(width 0.1)
				(type default)
			)
			(layer "F.Fab")
		)
		(fp_line
			(start -0.12065 -0.2794)
			(end 0.12065 -0.2794)
			(stroke
				(width 0.1)
				(type default)
			)
			(layer "F.Fab")
		)
		(fp_line
			(start 0.12065 -0.2794)
			(end 0.12065 -0.3048)
			(stroke
				(width 0.1)
				(type default)
			)
			(layer "F.Fab")
		)
		(fp_line
			(start 0.12065 -0.3048)
			(end 0.67945 -0.3048)
			(stroke
				(width 0.1)
				(type default)
			)
			(layer "F.Fab")
		)
		(fp_line
			(start 0.67945 -0.3048)
			(end 0.67945 0.3048)
			(stroke
				(width 0.1)
				(type default)
			)
			(layer "F.Fab")
		)
		(fp_line
			(start -0.67945 -0.305054)
			(end -0.12065 -0.305054)
			(stroke
				(width 0.1)
				(type default)
			)
			(layer "F.Fab")
		)
		(fp_line
			(start -0.12065 -0.305054)
			(end -0.12065 -0.2794)
			(stroke
				(width 0.1)
				(type default)
			)
			(layer "F.Fab")
		)
		(pad "1" smd circle
			(at -0.40005 0 270)
			(size 0 0)
			(layers "F.Cu" "F.Mask" "F.Paste")
			(net "SW_PVCCFA_EHV_FIVRA_CPU1_BOOT2_")
		)
		(pad "2" smd circle
			(at 0.40005 0 270)
			(size 0 0)
			(layers "F.Cu" "F.Mask" "F.Paste")
			(net "SW_PVCCFA_EHV_FIVRA_CPU1_BOOTR2")
		)
	)
	(footprint ""
		(layer "F.Cu")
		(at 367.411 -54.828948)
		(property "Reference" "R754"
			(at 0 0 0)
			(layer "F.SilkS")
			(hide yes)
			(effects
				(font
					(size 1.27 1.27)
				)
			)
		)
		(property "Value" ""
			(at 0 0 0)
			(layer "F.Fab")
			(effects
				(font
					(size 1.27 1.27)
				)
			)
		)
		(duplicate_pad_numbers_are_jumpers no)
		(fp_line
			(start -0.7874 -0.4064)
			(end 0.7874 -0.4064)
			(stroke
				(width 0.1524)
				(type default)
			)
			(layer "F.SilkS")
		)
		(fp_line
			(start -0.7874 0.4064)
			(end -0.7874 -0.4064)
			(stroke
				(width 0.1524)
				(type default)
			)
			(layer "F.SilkS")
		)
		(fp_line
			(start 0.7874 -0.4064)
			(end 0.7874 0.4064)
			(stroke
				(width 0.1524)
				(type default)
			)
			(layer "F.SilkS")
		)
		(fp_line
			(start 0.7874 0.4064)
			(end -0.7874 0.4064)
			(stroke
				(width 0.1524)
				(type default)
			)
			(layer "F.SilkS")
		)
		(fp_line
			(start -0.67945 -0.305054)
			(end -0.12065 -0.305054)
			(stroke
				(width 0.1)
				(type default)
			)
			(layer "F.Fab")
		)
		(fp_line
			(start -0.67945 0.3048)
			(end -0.67945 -0.305054)
			(stroke
				(width 0.1)
				(type default)
			)
			(layer "F.Fab")
		)
		(fp_line
			(start -0.12065 -0.305054)
			(end -0.12065 -0.2794)
			(stroke
				(width 0.1)
				(type default)
			)
			(layer "F.Fab")
		)
		(fp_line
			(start -0.12065 -0.2794)
			(end 0.12065 -0.2794)
			(stroke
				(width 0.1)
				(type default)
			)
			(layer "F.Fab")
		)
		(fp_line
			(start -0.12065 0.2794)
			(end -0.12065 0.3048)
			(stroke
				(width 0.1)
				(type default)
			)
			(layer "F.Fab")
		)
		(fp_line
			(start -0.12065 0.3048)
			(end -0.67945 0.3048)
			(stroke
				(width 0.1)
				(type default)
			)
			(layer "F.Fab")
		)
		(fp_line
			(start 0.120396 0.2794)
			(end -0.12065 0.2794)
			(stroke
				(width 0.1)
				(type default)
			)
			(layer "F.Fab")
		)
		(fp_line
			(start 0.120396 0.3048)
			(end 0.120396 0.2794)
			(stroke
				(width 0.1)
				(type default)
			)
			(layer "F.Fab")
		)
		(fp_line
			(start 0.12065 -0.3048)
			(end 0.67945 -0.3048)
			(stroke
				(width 0.1)
				(type default)
			)
			(layer "F.Fab")
		)
		(fp_line
			(start 0.12065 -0.2794)
			(end 0.12065 -0.3048)
			(stroke
				(width 0.1)
				(type default)
			)
			(layer "F.Fab")
		)
		(fp_line
			(start 0.67945 -0.3048)
			(end 0.67945 0.3048)
			(stroke
				(width 0.1)
				(type default)
			)
			(layer "F.Fab")
		)
		(fp_line
			(start 0.67945 0.3048)
			(end 0.120396 0.3048)
			(stroke
				(width 0.1)
				(type default)
			)
			(layer "F.Fab")
		)
		(pad "1" smd circle
			(at -0.40005 0)
			(size 0 0)
			(layers "F.Cu" "F.Mask" "F.Paste")
			(net "JTAG_DBP_TMS")
		)
		(pad "2" smd circle
			(at 0.40005 0)
			(size 0 0)
			(layers "F.Cu" "F.Mask" "F.Paste")
			(net "JTAG_DBP_TMS_PCH")
		)
	)
	(footprint ""
		(layer "F.Cu")
		(at 400.558 -152.339548)
		(property "Reference" "PC2180"
			(at 0 0 0)
			(layer "F.SilkS")
			(hide yes)
			(effects
				(font
					(size 1.27 1.27)
				)
			)
		)
		(property "Value" ""
			(at 0 0 0)
			(layer "F.Fab")
			(effects
				(font
					(size 1.27 1.27)
				)
			)
		)
		(duplicate_pad_numbers_are_jumpers no)
		(fp_line
			(start 2.750058 0.999998)
			(end -2.750058 0.999998)
			(stroke
				(width 0.1524)
				(type default)
			)
			(layer "F.SilkS")
		)
		(fp_circle
			(center 0 0.999998)
			(end 2.750058 0.999998)
			(stroke
				(width 0.1524)
				(type default)
			)
			(fill no)
			(layer "F.SilkS")
		)
		(fp_poly
			(pts
				(arc
					(start 2.750058 0.999998)
					(mid 0 3.750056)
					(end -2.750058 0.999998)
				)
			)
			(stroke
				(width 0)
				(type default)
			)
			(fill yes)
			(layer "F.SilkS")
		)
		(fp_circle
			(center 0 0.999998)
			(end 2.750058 0.999998)
			(stroke
				(width 0.1)
				(type default)
			)
			(fill no)
			(layer "F.Fab")
		)
		(pad "1" thru_hole rect
			(at 0 0)
			(size 1.5748 1.5748)
			(drill 1.0668)
			(layers "*.Cu" "*.Mask")
			(remove_unused_layers no)
			(net "PVCCFA_EHV_CPU0")
			(clearance 0)
			(padstack
				(mode front_inner_back)
				(layer "Inner"
					(shape circle)
					(size 1.5748 1.5748)
					(clearance 0)
				)
				(layer "B.Cu"
					(shape rect)
					(size 1.5748 1.5748)
					(clearance 0)
				)
			)
		)
		(pad "2" thru_hole circle
			(at 0 1.999996)
			(size 1.5748 1.5748)
			(drill 1.0668)
			(layers "*.Cu" "*.Mask")
			(remove_unused_layers no)
			(net "GND")
			(clearance 0)
		)
	)
)
